(kicad_pcb
	(version 20260206)
	(generator "pcbnew")
	(generator_version "10.0")
	(general
		(thickness 1.6)
		(legacy_teardrops no)
	)
	(paper "A4")
	(title_block
		(title "Wiwynn_Tioga_Pass_MB.brd")
		(comment 1 "Tioga Pass / footprint 2254 of 4770 (U5D1), pads 2827-2913 of 3647")
	)
	(layers
		(0 "F.Cu" signal "TOP")
		(4 "In1.Cu" signal "L2GND")
		(6 "In2.Cu" signal "L3")
		(8 "In3.Cu" signal "L4GND")
		(10 "In4.Cu" signal "L5")
		(12 "In5.Cu" signal "L6GND")
		(14 "In6.Cu" signal "L7VCC")
		(16 "In7.Cu" signal "L8VCC")
		(18 "In8.Cu" signal "L9GND")
		(20 "In9.Cu" signal "L10")
		(22 "In10.Cu" signal "L11GND")
		(24 "In11.Cu" signal "L12")
		(26 "In12.Cu" signal "L13GND")
		(2 "B.Cu" signal "BOTTOM")
		(9 "F.Adhes" user "F.Adhesive")
		(11 "B.Adhes" user "B.Adhesive")
		(13 "F.Paste" user "Package Geometry/Pastemask Top")
		(15 "B.Paste" user "Package Geometry/Pastemask Bottom")
		(5 "F.SilkS" user "Ref Des/Silkscreen Top")
		(7 "B.SilkS" user "Ref Des/Silkscreen Bottom")
		(1 "F.Mask" user "Board Geometry/Soldermask Top")
		(3 "B.Mask" user "Board Geometry/Soldermask Bottom")
		(17 "Dwgs.User" user "User.Drawings")
		(19 "Cmts.User" user "User.Comments")
		(21 "Eco1.User" user "User.Eco1")
		(23 "Eco2.User" user "User.Eco2")
		(25 "Edge.Cuts" user "Board Geometry/Outline")
		(27 "Margin" user)
		(31 "F.CrtYd" user "Package Geometry/Place Bound Top")
		(29 "B.CrtYd" user "Package Geometry/Place Bound Bottom")
		(35 "F.Fab" user "Ref Des/Assembly Top")
		(33 "B.Fab" user "Ref Des/Assembly Bottom")
	)
	(footprint ""
		(layer "F.Cu")
		(at 270.000222 -76.550012 180)
		(property "Reference" "U5D1"
			(at 19.124422 31.601918 0)
			(unlocked yes)
			(layer "F.SilkS")
			(effects
				(font
					(size 0.7874 0.5842)
					(thickness 0.1524)
				)
			)
		)
		(property "Value" ""
			(at 0 0 180)
			(layer "F.Fab")
			(effects
				(font
					(size 1.27 1.27)
				)
			)
		)
		(duplicate_pad_numbers_are_jumpers no)
		(pad "EA32" smd circle
			(at -10.637012 24.426672)
			(size 0.4318 0.4318)
			(layers "F.Cu" "F.Mask" "F.Paste")
			(net "M_E_DQS_DN<14>")
		)
		(pad "EA34" smd circle
			(at -8.919972 24.426672)
			(size 0.4318 0.4318)
			(layers "F.Cu" "F.Mask" "F.Paste")
			(net "M_E_DQ<45>")
		)
		(pad "EA36" smd circle
			(at -7.202932 24.426672)
			(size 0.4318 0.4318)
			(layers "F.Cu" "F.Mask" "F.Paste")
			(net "M_D_DQ<34>")
		)
		(pad "EA38" smd circle
			(at -5.485892 24.426672)
			(size 0.4318 0.4318)
			(layers "F.Cu" "F.Mask" "F.Paste")
			(net "M_D_DQS_DN<13>")
		)
		(pad "EA40" smd circle
			(at -3.769106 24.426672)
			(size 0.4318 0.4318)
			(layers "F.Cu" "F.Mask" "F.Paste")
			(net "M_D_DQ<37>")
		)
		(pad "EA42" smd circle
			(at -2.052066 24.426672)
			(size 0.4318 0.4318)
			(layers "F.Cu" "F.Mask" "F.Paste")
			(net "GND")
		)
		(pad "EA44" smd circle
			(at 1.193546 22.626828)
			(size 0.508 0.508)
			(layers "F.Cu" "F.Mask" "F.Paste")
			(net "TP_CPU0_RSVD_19")
		)
		(pad "EA46" smd circle
			(at 2.910586 22.626828)
			(size 0.4318 0.4318)
			(layers "F.Cu" "F.Mask" "F.Paste")
			(net "M_D_MA<17>")
		)
		(pad "EA48" smd circle
			(at 4.627626 22.626828)
			(size 0.4318 0.4318)
			(layers "F.Cu" "F.Mask" "F.Paste")
			(net "M_D_ODT<3>")
		)
		(pad "EA50" smd circle
			(at 6.344412 22.626828)
			(size 0.4318 0.4318)
			(layers "F.Cu" "F.Mask" "F.Paste")
			(net "M_D_ODT<2>")
		)
		(pad "EA52" smd circle
			(at 8.061452 22.626828)
			(size 0.4318 0.4318)
			(layers "F.Cu" "F.Mask" "F.Paste")
			(net "M_D_MA<16>")
		)
		(pad "EA54" smd circle
			(at 9.778492 22.626828)
			(size 0.4318 0.4318)
			(layers "F.Cu" "F.Mask" "F.Paste")
			(net "M_D_BA<1>")
		)
		(pad "EA56" smd circle
			(at 11.495532 22.626828)
			(size 0.4318 0.4318)
			(layers "F.Cu" "F.Mask" "F.Paste")
			(net "M_D_CLK_DP<2>")
		)
		(pad "EA58" smd circle
			(at 13.212572 22.626828)
			(size 0.4318 0.4318)
			(layers "F.Cu" "F.Mask" "F.Paste")
			(net "M_D_MA<5>")
		)
		(pad "EA60" smd circle
			(at 14.929612 22.626828)
			(size 0.4318 0.4318)
			(layers "F.Cu" "F.Mask" "F.Paste")
			(net "M_D_MA<7>")
		)
		(pad "EA62" smd circle
			(at 16.646398 22.626828)
			(size 0.4318 0.4318)
			(layers "F.Cu" "F.Mask" "F.Paste")
			(net "M_D_CKE<2>")
		)
		(pad "EA64" smd circle
			(at 18.363438 22.626828)
			(size 0.4318 0.4318)
			(layers "F.Cu" "F.Mask" "F.Paste")
			(net "GND")
		)
		(pad "EA66" smd circle
			(at 20.080478 22.626828)
			(size 0.4318 0.4318)
			(layers "F.Cu" "F.Mask" "F.Paste")
			(net "M_E_ECC<7>")
		)
		(pad "EA68" smd circle
			(at 21.797518 22.626828)
			(size 0.4318 0.4318)
			(layers "F.Cu" "F.Mask" "F.Paste")
			(net "M_E_ECC<1>")
		)
		(pad "EA70" smd circle
			(at 23.514558 22.626828)
			(size 0.4318 0.4318)
			(layers "F.Cu" "F.Mask" "F.Paste")
			(net "GND")
		)
		(pad "EA72" smd circle
			(at 25.231598 22.626828)
			(size 0.4318 0.4318)
			(layers "F.Cu" "F.Mask" "F.Paste")
			(net "M_E_DQ<30>")
		)
		(pad "EA74" smd circle
			(at 26.948384 22.626828)
			(size 0.4318 0.4318)
			(layers "F.Cu" "F.Mask" "F.Paste")
			(net "M_E_DQ<28>")
		)
		(pad "EA76" smd circle
			(at 28.665424 22.626828)
			(size 0.4318 0.4318)
			(layers "F.Cu" "F.Mask" "F.Paste")
			(net "GND")
		)
		(pad "EA78" smd circle
			(at 30.382464 22.626828)
			(size 0.4318 0.4318)
			(layers "F.Cu" "F.Mask" "F.Paste")
			(net "GND")
		)
		(pad "EA80" smd circle
			(at 32.099504 22.626828)
			(size 0.4318 0.4318)
			(layers "F.Cu" "F.Mask" "F.Paste")
			(net "GND")
		)
		(pad "EA82" smd circle
			(at 33.816544 22.626828)
			(size 0.4318 0.4318)
			(layers "F.Cu" "F.Mask" "F.Paste")
			(net "GND")
		)
		(pad "EA84" smd custom
			(at 35.533584 22.626828 225)
			(size 0.10795 0.10795)
			(layers "F.Cu" "F.Mask" "F.Paste")
			(net "GND")
			(options
				(clearance outline)
				(anchor circle)
			)
			(primitives
				(gr_poly
					(pts
						(arc
							(start 0.2159 -0.0381)
							(mid 0 -0.254)
							(end -0.2159 -0.0381)
						)
						(arc
							(start -0.2159 0.0381)
							(mid 0 0.254)
							(end 0.2159 0.0381)
						)
					)
					(width 0)
					(fill yes)
				)
			)
		)
		(pad "EB3" smd custom
			(at -35.533584 24.921972 135)
			(size 0.10795 0.10795)
			(layers "F.Cu" "F.Mask" "F.Paste")
			(net "TP_CPU0_RSVD_18")
			(options
				(clearance outline)
				(anchor circle)
			)
			(primitives
				(gr_poly
					(pts
						(arc
							(start 0.2159 -0.0381)
							(mid 0 -0.254)
							(end -0.2159 -0.0381)
						)
						(arc
							(start -0.2159 0.0381)
							(mid 0 0.254)
							(end 0.2159 0.0381)
						)
					)
					(width 0)
					(fill yes)
				)
			)
		)
		(pad "EB5" smd custom
			(at -33.816544 24.921972 135)
			(size 0.10795 0.10795)
			(layers "F.Cu" "F.Mask" "F.Paste")
			(net "TP_CPU0_RSVD_17")
			(options
				(clearance outline)
				(anchor circle)
			)
			(primitives
				(gr_poly
					(pts
						(arc
							(start 0.2159 -0.0381)
							(mid 0 -0.254)
							(end -0.2159 -0.0381)
						)
						(arc
							(start -0.2159 0.0381)
							(mid 0 0.254)
							(end 0.2159 0.0381)
						)
					)
					(width 0)
					(fill yes)
				)
			)
		)
		(pad "EB7" smd circle
			(at -32.099504 24.921972)
			(size 0.4318 0.4318)
			(layers "F.Cu" "F.Mask" "F.Paste")
			(net "P3E_CPU0_PE1_PCH_TXP<14>")
		)
		(pad "EB9" smd circle
			(at -30.382464 24.921972)
			(size 0.4318 0.4318)
			(layers "F.Cu" "F.Mask" "F.Paste")
			(net "P3E_CPU0_PE3_OCP_TXN<4>")
		)
		(pad "EB11" smd circle
			(at -28.665424 24.921972)
			(size 0.4318 0.4318)
			(layers "F.Cu" "F.Mask" "F.Paste")
			(net "P3E_CPU0_PE3_OCP_TXP<2>")
		)
		(pad "EB13" smd circle
			(at -26.948384 24.921972)
			(size 0.4318 0.4318)
			(layers "F.Cu" "F.Mask" "F.Paste")
			(net "GND")
		)
		(pad "EB15" smd circle
			(at -25.231598 24.921972)
			(size 0.4318 0.4318)
			(layers "F.Cu" "F.Mask" "F.Paste")
			(net "PVCCIO_CPU0")
		)
		(pad "EB21" smd custom
			(at -20.080478 24.921972 120)
			(size 0.10795 0.10795)
			(layers "F.Cu" "F.Mask" "F.Paste")
			(net "M_D_DQ<59>")
			(options
				(clearance outline)
				(anchor circle)
			)
			(primitives
				(gr_poly
					(pts
						(arc
							(start 0.2159 -0.0381)
							(mid 0 -0.254)
							(end -0.2159 -0.0381)
						)
						(arc
							(start -0.2159 0.0381)
							(mid 0 0.254)
							(end 0.2159 0.0381)
						)
					)
					(width 0)
					(fill yes)
				)
			)
		)
		(pad "EB23" smd circle
			(at -18.363438 24.921972)
			(size 0.4318 0.4318)
			(layers "F.Cu" "F.Mask" "F.Paste")
			(net "GND")
		)
		(pad "EB25" smd circle
			(at -16.646398 24.921972)
			(size 0.4318 0.4318)
			(layers "F.Cu" "F.Mask" "F.Paste")
			(net "GND")
		)
		(pad "EB27" smd circle
			(at -14.929612 24.921972)
			(size 0.4318 0.4318)
			(layers "F.Cu" "F.Mask" "F.Paste")
			(net "GND")
		)
		(pad "EB29" smd circle
			(at -13.212572 24.921972)
			(size 0.4318 0.4318)
			(layers "F.Cu" "F.Mask" "F.Paste")
			(net "GND")
		)
		(pad "EB31" smd circle
			(at -11.495532 24.921972)
			(size 0.4318 0.4318)
			(layers "F.Cu" "F.Mask" "F.Paste")
			(net "GND")
		)
		(pad "EB33" smd circle
			(at -9.778492 24.921972)
			(size 0.4318 0.4318)
			(layers "F.Cu" "F.Mask" "F.Paste")
			(net "GND")
		)
		(pad "EB35" smd circle
			(at -8.061452 24.921972)
			(size 0.4318 0.4318)
			(layers "F.Cu" "F.Mask" "F.Paste")
			(net "GND")
		)
		(pad "EB37" smd circle
			(at -6.344412 24.921972)
			(size 0.4318 0.4318)
			(layers "F.Cu" "F.Mask" "F.Paste")
			(net "GND")
		)
		(pad "EB39" smd circle
			(at -4.627626 24.921972)
			(size 0.4318 0.4318)
			(layers "F.Cu" "F.Mask" "F.Paste")
			(net "GND")
		)
		(pad "EB41" smd circle
			(at -2.910586 24.921972)
			(size 0.4318 0.4318)
			(layers "F.Cu" "F.Mask" "F.Paste")
			(net "GND")
		)
		(pad "EB45" smd circle
			(at 2.052066 23.122128)
			(size 0.4318 0.4318)
			(layers "F.Cu" "F.Mask" "F.Paste")
			(net "M_D_CS_N<7>")
		)
		(pad "EB47" smd circle
			(at 3.769106 23.122128)
			(size 0.4318 0.4318)
			(layers "F.Cu" "F.Mask" "F.Paste")
			(net "M_D_CS_N<3>")
		)
		(pad "EB49" smd circle
			(at 5.485892 23.122128)
			(size 0.4318 0.4318)
			(layers "F.Cu" "F.Mask" "F.Paste")
			(net "M_D_CS_N<5>")
		)
		(pad "EB51" smd circle
			(at 7.202932 23.122128)
			(size 0.4318 0.4318)
			(layers "F.Cu" "F.Mask" "F.Paste")
			(net "M_D_CS_N<4>")
		)
		(pad "EB53" smd circle
			(at 8.919972 23.122128)
			(size 0.4318 0.4318)
			(layers "F.Cu" "F.Mask" "F.Paste")
			(net "M_D_MA<0>")
		)
		(pad "EB55" smd circle
			(at 10.637012 23.122128)
			(size 0.4318 0.4318)
			(layers "F.Cu" "F.Mask" "F.Paste")
			(net "M_D_CLK_DP<0>")
		)
		(pad "EB57" smd circle
			(at 12.354052 23.122128)
			(size 0.4318 0.4318)
			(layers "F.Cu" "F.Mask" "F.Paste")
			(net "M_D_MA<3>")
		)
		(pad "EB59" smd circle
			(at 14.071092 23.122128)
			(size 0.4318 0.4318)
			(layers "F.Cu" "F.Mask" "F.Paste")
			(net "M_D_MA<8>")
		)
		(pad "EB61" smd circle
			(at 15.787878 23.122128)
			(size 0.4318 0.4318)
			(layers "F.Cu" "F.Mask" "F.Paste")
			(net "M_D_MA<11>")
		)
		(pad "EB63" smd custom
			(at 17.504918 23.122128 180)
			(size 0.10795 0.10795)
			(layers "F.Cu" "F.Mask" "F.Paste")
			(net "M_D_CKE<3>")
			(options
				(clearance outline)
				(anchor circle)
			)
			(primitives
				(gr_poly
					(pts
						(arc
							(start 0.2159 -0.0381)
							(mid 0 -0.254)
							(end -0.2159 -0.0381)
						)
						(arc
							(start -0.2159 0.0381)
							(mid 0 0.254)
							(end 0.2159 0.0381)
						)
					)
					(width 0)
					(fill yes)
				)
			)
		)
		(pad "EB65" smd custom
			(at 19.221958 23.122128 180)
			(size 0.10795 0.10795)
			(layers "F.Cu" "F.Mask" "F.Paste")
			(net "GND")
			(options
				(clearance outline)
				(anchor circle)
			)
			(primitives
				(gr_poly
					(pts
						(arc
							(start 0.2159 -0.0381)
							(mid 0 -0.254)
							(end -0.2159 -0.0381)
						)
						(arc
							(start -0.2159 0.0381)
							(mid 0 0.254)
							(end 0.2159 0.0381)
						)
					)
					(width 0)
					(fill yes)
				)
			)
		)
		(pad "EB67" smd custom
			(at 20.938998 23.122128 180)
			(size 0.10795 0.10795)
			(layers "F.Cu" "F.Mask" "F.Paste")
			(net "M_E_DQS_DN<8>")
			(options
				(clearance outline)
				(anchor circle)
			)
			(primitives
				(gr_poly
					(pts
						(arc
							(start 0.2159 -0.0381)
							(mid 0 -0.254)
							(end -0.2159 -0.0381)
						)
						(arc
							(start -0.2159 0.0381)
							(mid 0 0.254)
							(end 0.2159 0.0381)
						)
					)
					(width 0)
					(fill yes)
				)
			)
		)
		(pad "EB69" smd custom
			(at 22.656038 23.122128 180)
			(size 0.10795 0.10795)
			(layers "F.Cu" "F.Mask" "F.Paste")
			(net "GND")
			(options
				(clearance outline)
				(anchor circle)
			)
			(primitives
				(gr_poly
					(pts
						(arc
							(start 0.2159 -0.0381)
							(mid 0 -0.254)
							(end -0.2159 -0.0381)
						)
						(arc
							(start -0.2159 0.0381)
							(mid 0 0.254)
							(end 0.2159 0.0381)
						)
					)
					(width 0)
					(fill yes)
				)
			)
		)
		(pad "EB71" smd circle
			(at 24.373078 23.122128)
			(size 0.4318 0.4318)
			(layers "F.Cu" "F.Mask" "F.Paste")
			(net "M_E_DQ<26>")
		)
		(pad "EB73" smd circle
			(at 26.090118 23.122128)
			(size 0.4318 0.4318)
			(layers "F.Cu" "F.Mask" "F.Paste")
			(net "M_E_DQS_DN<12>")
		)
		(pad "EB75" smd circle
			(at 27.806904 23.122128)
			(size 0.4318 0.4318)
			(layers "F.Cu" "F.Mask" "F.Paste")
			(net "M_E_DQ<29>")
		)
		(pad "EB77" smd circle
			(at 29.523944 23.122128)
			(size 0.4318 0.4318)
			(layers "F.Cu" "F.Mask" "F.Paste")
			(net "M_E_DQ<19>")
		)
		(pad "EB79" smd circle
			(at 31.240984 23.122128)
			(size 0.4318 0.4318)
			(layers "F.Cu" "F.Mask" "F.Paste")
			(net "M_E_DQS_DP<2>")
		)
		(pad "EB81" smd circle
			(at 32.958024 23.122128)
			(size 0.4318 0.4318)
			(layers "F.Cu" "F.Mask" "F.Paste")
			(net "M_E_DQ<21>")
		)
		(pad "EB83" smd custom
			(at 34.675064 23.122128 225)
			(size 0.10795 0.10795)
			(layers "F.Cu" "F.Mask" "F.Paste")
			(net "GND")
			(options
				(clearance outline)
				(anchor circle)
			)
			(primitives
				(gr_poly
					(pts
						(arc
							(start 0.2159 -0.0381)
							(mid 0 -0.254)
							(end -0.2159 -0.0381)
						)
						(arc
							(start -0.2159 0.0381)
							(mid 0 0.254)
							(end 0.2159 0.0381)
						)
					)
					(width 0)
					(fill yes)
				)
			)
		)
		(pad "EB85" smd custom
			(at 36.392104 23.122128 270)
			(size 0.10795 0.10795)
			(layers "F.Cu" "F.Mask" "F.Paste")
			(net "TP_CPU0_RSVD_16")
			(options
				(clearance outline)
				(anchor circle)
			)
			(primitives
				(gr_poly
					(pts
						(arc
							(start 0.2159 -0.0381)
							(mid 0 -0.254)
							(end -0.2159 -0.0381)
						)
						(arc
							(start -0.2159 0.0381)
							(mid 0 0.254)
							(end 0.2159 0.0381)
						)
					)
					(width 0)
					(fill yes)
				)
			)
		)
		(pad "EC4" smd custom
			(at -34.675064 25.417526 135)
			(size 0.10795 0.10795)
			(layers "F.Cu" "F.Mask" "F.Paste")
			(net "TP_CPU0_RSVD_14")
			(options
				(clearance outline)
				(anchor circle)
			)
			(primitives
				(gr_poly
					(pts
						(arc
							(start 0.2159 -0.0381)
							(mid 0 -0.254)
							(end -0.2159 -0.0381)
						)
						(arc
							(start -0.2159 0.0381)
							(mid 0 0.254)
							(end 0.2159 0.0381)
						)
					)
					(width 0)
					(fill yes)
				)
			)
		)
		(pad "EC6" smd custom
			(at -32.958024 25.417526 135)
			(size 0.10795 0.10795)
			(layers "F.Cu" "F.Mask" "F.Paste")
			(net "GND")
			(options
				(clearance outline)
				(anchor circle)
			)
			(primitives
				(gr_poly
					(pts
						(arc
							(start 0.2159 -0.0381)
							(mid 0 -0.254)
							(end -0.2159 -0.0381)
						)
						(arc
							(start -0.2159 0.0381)
							(mid 0 0.254)
							(end 0.2159 0.0381)
						)
					)
					(width 0)
					(fill yes)
				)
			)
		)
		(pad "EC8" smd circle
			(at -31.240984 25.417526)
			(size 0.4318 0.4318)
			(layers "F.Cu" "F.Mask" "F.Paste")
			(net "P3E_CPU0_PE1_PCH_TXP<15>")
		)
		(pad "EC10" smd circle
			(at -29.523944 25.417526)
			(size 0.4318 0.4318)
			(layers "F.Cu" "F.Mask" "F.Paste")
			(net "GND")
		)
		(pad "EC12" smd circle
			(at -27.806904 25.417526)
			(size 0.4318 0.4318)
			(layers "F.Cu" "F.Mask" "F.Paste")
			(net "P3E_CPU0_PE3_OCP_TXN<2>")
		)
		(pad "EC14" smd circle
			(at -26.090118 25.417526)
			(size 0.4318 0.4318)
			(layers "F.Cu" "F.Mask" "F.Paste")
			(net "P3E_CPU0_PE3_OCP_TXP<0>")
		)
		(pad "EC16" smd custom
			(at -24.373078 25.417526 180)
			(size 0.10795 0.10795)
			(layers "F.Cu" "F.Mask" "F.Paste")
			(net "TP_CPU0_RSVD_15")
			(options
				(clearance outline)
				(anchor circle)
			)
			(primitives
				(gr_poly
					(pts
						(arc
							(start 0.2159 -0.0381)
							(mid 0 -0.254)
							(end -0.2159 -0.0381)
						)
						(arc
							(start -0.2159 0.0381)
							(mid 0 0.254)
							(end 0.2159 0.0381)
						)
					)
					(width 0)
					(fill yes)
				)
			)
		)
		(pad "EC22" smd custom
			(at -19.221958 25.417526 120)
			(size 0.10795 0.10795)
			(layers "F.Cu" "F.Mask" "F.Paste")
			(net "M_D_DQ<62>")
			(options
				(clearance outline)
				(anchor circle)
			)
			(primitives
				(gr_poly
					(pts
						(arc
							(start 0.2159 -0.0381)
							(mid 0 -0.254)
							(end -0.2159 -0.0381)
						)
						(arc
							(start -0.2159 0.0381)
							(mid 0 0.254)
							(end 0.2159 0.0381)
						)
					)
					(width 0)
					(fill yes)
				)
			)
		)
		(pad "EC24" smd circle
			(at -17.504918 25.417526)
			(size 0.4318 0.4318)
			(layers "F.Cu" "F.Mask" "F.Paste")
			(net "M_E_DQ<51>")
		)
		(pad "EC26" smd circle
			(at -15.787878 25.417526)
			(size 0.4318 0.4318)
			(layers "F.Cu" "F.Mask" "F.Paste")
			(net "M_E_DQS_DP<6>")
		)
		(pad "EC28" smd circle
			(at -14.071092 25.417526)
			(size 0.4318 0.4318)
			(layers "F.Cu" "F.Mask" "F.Paste")
			(net "M_E_DQ<48>")
		)
		(pad "EC30" smd circle
			(at -12.354052 25.417526)
			(size 0.4318 0.4318)
			(layers "F.Cu" "F.Mask" "F.Paste")
			(net "M_E_DQ<43>")
		)
		(pad "EC32" smd circle
			(at -10.637012 25.417526)
			(size 0.4318 0.4318)
			(layers "F.Cu" "F.Mask" "F.Paste")
			(net "M_E_DQS_DP<5>")
		)
		(pad "EC34" smd circle
			(at -8.919972 25.417526)
			(size 0.4318 0.4318)
			(layers "F.Cu" "F.Mask" "F.Paste")
			(net "M_E_DQ<40>")
		)
		(pad "EC36" smd circle
			(at -7.202932 25.417526)
			(size 0.4318 0.4318)
			(layers "F.Cu" "F.Mask" "F.Paste")
			(net "M_D_DQ<35>")
		)
		(pad "EC38" smd circle
			(at -5.485892 25.417526)
			(size 0.4318 0.4318)
			(layers "F.Cu" "F.Mask" "F.Paste")
			(net "M_D_DQS_DP<4>")
		)
		(pad "EC40" smd circle
			(at -3.769106 25.417526)
			(size 0.4318 0.4318)
			(layers "F.Cu" "F.Mask" "F.Paste")
			(net "M_D_DQ<32>")
		)
		(pad "EC42" smd custom
			(at -2.052066 25.417526 225)
			(size 0.10795 0.10795)
			(layers "F.Cu" "F.Mask" "F.Paste")
			(net "GND")
			(options
				(clearance outline)
				(anchor circle)
			)
			(primitives
				(gr_poly
					(pts
						(arc
							(start 0.2159 -0.0381)
							(mid 0 -0.254)
							(end -0.2159 -0.0381)
						)
						(arc
							(start -0.2159 0.0381)
							(mid 0 0.254)
							(end 0.2159 0.0381)
						)
					)
					(width 0)
					(fill yes)
				)
			)
		)
		(pad "EC44" smd circle
			(at 1.193546 23.617174)
			(size 0.508 0.508)
			(layers "F.Cu" "F.Mask" "F.Paste")
			(net "TP_CPU0_RSVD_13")
		)
		(pad "EC46" smd circle
			(at 2.910586 23.617174)
			(size 0.4318 0.4318)
			(layers "F.Cu" "F.Mask" "F.Paste")
			(net "PVDDQ_DEF")
		)
		(pad "EC48" smd circle
			(at 4.627626 23.617174)
			(size 0.4318 0.4318)
			(layers "F.Cu" "F.Mask" "F.Paste")
			(net "PVDDQ_DEF")
		)
	)
)
